(kicad_pcb
	(version 20260206)
	(generator "pcbnew")
	(generator_version "10.0")
	(general
		(thickness 1.6)
		(legacy_teardrops no)
	)
	(paper "A4")
	(title_block
		(title "12092022_DA0F0TMDCD0_F0T_Management_Board_D_brd_V3_OCP.brd")
		(comment 1 "Grand Teton / footprints 1041-1046 of 1440")
	)
	(layers
		(0 "F.Cu" signal "TOP")
		(4 "In1.Cu" signal "GND")
		(6 "In2.Cu" signal "IN1")
		(8 "In3.Cu" signal "GND1")
		(10 "In4.Cu" signal "IN2")
		(12 "In5.Cu" signal "VCC")
		(14 "In6.Cu" signal "VCC1")
		(16 "In7.Cu" signal "IN3")
		(18 "In8.Cu" signal "GND2")
		(20 "In9.Cu" signal "IN4")
		(22 "In10.Cu" signal "GND3")
		(2 "B.Cu" signal "BOTTOM")
		(9 "F.Adhes" user "F.Adhesive")
		(11 "B.Adhes" user "B.Adhesive")
		(13 "F.Paste" user "Package Geometry/Pastemask Top")
		(15 "B.Paste" user "Package Geometry/Pastemask Bottom")
		(5 "F.SilkS" user "Ref Des/Silkscreen Top")
		(7 "B.SilkS" user "Ref Des/Silkscreen Bottom")
		(1 "F.Mask" user "Board Geometry/Soldermask Top")
		(3 "B.Mask" user "Board Geometry/Soldermask Bottom")
		(17 "Dwgs.User" user "User.Drawings")
		(19 "Cmts.User" user "User.Comments")
		(21 "Eco1.User" user "User.Eco1")
		(23 "Eco2.User" user "User.Eco2")
		(25 "Edge.Cuts" user "Board Geometry/Outline")
		(27 "Margin" user)
		(31 "F.CrtYd" user "Package Geometry/Place Bound Top")
		(29 "B.CrtYd" user "Package Geometry/Place Bound Bottom")
		(35 "F.Fab" user "Ref Des/Assembly Top")
		(33 "B.Fab" user "Ref Des/Assembly Bottom")
	)
	(footprint ""
		(layer "B.Cu")
		(at 26.659332 -88.787224 -90)
		(property "Reference" "C269"
			(at 0 0 90)
			(layer "B.SilkS")
			(hide yes)
			(effects
				(font
					(size 1.27 1.27)
				)
				(justify mirror)
			)
		)
		(property "Value" ""
			(at 0 0 90)
			(layer "B.Fab")
			(effects
				(font
					(size 1.27 1.27)
				)
				(justify mirror)
			)
		)
		(duplicate_pad_numbers_are_jumpers no)
		(fp_line
			(start -0.69215 0.2921)
			(end 0.69215 0.2921)
			(stroke
				(width 0.1524)
				(type default)
			)
			(layer "B.SilkS")
		)
		(fp_line
			(start 0.69215 0.2921)
			(end 0.69215 -0.2921)
			(stroke
				(width 0.1524)
				(type default)
			)
			(layer "B.SilkS")
		)
		(fp_line
			(start -0.69215 -0.2921)
			(end -0.69215 0.2921)
			(stroke
				(width 0.1524)
				(type default)
			)
			(layer "B.SilkS")
		)
		(fp_line
			(start 0.69215 -0.2921)
			(end -0.69215 -0.2921)
			(stroke
				(width 0.1524)
				(type default)
			)
			(layer "B.SilkS")
		)
		(fp_line
			(start -0.51435 0.2794)
			(end 0.51435 0.2794)
			(stroke
				(width 0.1)
				(type default)
			)
			(layer "B.Fab")
		)
		(fp_line
			(start 0.51435 0.2794)
			(end 0.51435 -0.2794)
			(stroke
				(width 0.1)
				(type default)
			)
			(layer "B.Fab")
		)
		(fp_line
			(start -0.51435 -0.2794)
			(end -0.51435 0.2794)
			(stroke
				(width 0.1)
				(type default)
			)
			(layer "B.Fab")
		)
		(fp_line
			(start 0.51435 -0.2794)
			(end -0.51435 -0.2794)
			(stroke
				(width 0.1)
				(type default)
			)
			(layer "B.Fab")
		)
		(pad "1" smd circle
			(at 0.40005 0 90)
			(size 0 0)
			(layers "B.Cu" "B.Mask" "B.Paste")
			(net "PVCCA_AUX_PLD")
		)
		(pad "2" smd circle
			(at -0.40005 0 90)
			(size 0 0)
			(layers "B.Cu" "B.Mask" "B.Paste")
			(net "GND")
		)
		(zone
			(layer "B.Cu")
			(hatch none 0.5)
			(connect_pads
				(clearance 0)
			)
			(min_thickness 0.25)
			(keepout
				(tracks not_allowed)
				(vias allowed)
				(pads allowed)
				(copperpour not_allowed)
				(footprints allowed)
			)
			(placement
				(enabled no)
				(sheetname "")
			)
			(fill
				(thermal_gap 0.5)
				(thermal_bridge_width 0.5)
				(island_removal_mode 0)
			)
			(polygon
				(pts
					(xy 26.571702 -88.596724) (xy 26.513536 -88.688164) (xy 26.513536 -88.887554) (xy 26.571702 -88.977724)
					(xy 26.746962 -88.977724) (xy 26.805382 -88.887554) (xy 26.805382 -88.688164) (xy 26.747216 -88.596724)
				)
			)
		)
	)
	(footprint ""
		(layer "B.Cu")
		(at 79.8576 -30.988)
		(property "Reference" "R700"
			(at 0 0 0)
			(layer "B.SilkS")
			(hide yes)
			(effects
				(font
					(size 1.27 1.27)
				)
				(justify mirror)
			)
		)
		(property "Value" ""
			(at 0 0 0)
			(layer "B.Fab")
			(effects
				(font
					(size 1.27 1.27)
				)
				(justify mirror)
			)
		)
		(duplicate_pad_numbers_are_jumpers no)
		(fp_line
			(start -0.7874 -0.4064)
			(end -0.7874 0.4064)
			(stroke
				(width 0.1524)
				(type default)
			)
			(layer "B.SilkS")
		)
		(fp_line
			(start -0.7874 0.4064)
			(end 0.7874 0.4064)
			(stroke
				(width 0.1524)
				(type default)
			)
			(layer "B.SilkS")
		)
		(fp_line
			(start 0.7874 -0.4064)
			(end -0.7874 -0.4064)
			(stroke
				(width 0.1524)
				(type default)
			)
			(layer "B.SilkS")
		)
		(fp_line
			(start 0.7874 0.4064)
			(end 0.7874 -0.4064)
			(stroke
				(width 0.1524)
				(type default)
			)
			(layer "B.SilkS")
		)
		(fp_line
			(start -0.67945 -0.3048)
			(end -0.67945 0.3048)
			(stroke
				(width 0.1)
				(type default)
			)
			(layer "B.Fab")
		)
		(fp_line
			(start -0.67945 0.3048)
			(end -0.120396 0.3048)
			(stroke
				(width 0.1)
				(type default)
			)
			(layer "B.Fab")
		)
		(fp_line
			(start -0.12065 -0.3048)
			(end -0.67945 -0.3048)
			(stroke
				(width 0.1)
				(type default)
			)
			(layer "B.Fab")
		)
		(fp_line
			(start -0.12065 -0.2794)
			(end -0.12065 -0.3048)
			(stroke
				(width 0.1)
				(type default)
			)
			(layer "B.Fab")
		)
		(fp_line
			(start -0.120396 0.2794)
			(end 0.12065 0.2794)
			(stroke
				(width 0.1)
				(type default)
			)
			(layer "B.Fab")
		)
		(fp_line
			(start -0.120396 0.3048)
			(end -0.120396 0.2794)
			(stroke
				(width 0.1)
				(type default)
			)
			(layer "B.Fab")
		)
		(fp_line
			(start 0.12065 -0.305054)
			(end 0.12065 -0.2794)
			(stroke
				(width 0.1)
				(type default)
			)
			(layer "B.Fab")
		)
		(fp_line
			(start 0.12065 -0.2794)
			(end -0.12065 -0.2794)
			(stroke
				(width 0.1)
				(type default)
			)
			(layer "B.Fab")
		)
		(fp_line
			(start 0.12065 0.2794)
			(end 0.12065 0.3048)
			(stroke
				(width 0.1)
				(type default)
			)
			(layer "B.Fab")
		)
		(fp_line
			(start 0.12065 0.3048)
			(end 0.67945 0.3048)
			(stroke
				(width 0.1)
				(type default)
			)
			(layer "B.Fab")
		)
		(fp_line
			(start 0.67945 -0.305054)
			(end 0.12065 -0.305054)
			(stroke
				(width 0.1)
				(type default)
			)
			(layer "B.Fab")
		)
		(fp_line
			(start 0.67945 0.3048)
			(end 0.67945 -0.305054)
			(stroke
				(width 0.1)
				(type default)
			)
			(layer "B.Fab")
		)
		(pad "1" smd circle
			(at 0.40005 0 180)
			(size 0 0)
			(layers "B.Cu" "B.Mask" "B.Paste")
			(net "LED_POSTCODE_0")
		)
		(pad "2" smd circle
			(at -0.40005 0 180)
			(size 0 0)
			(layers "B.Cu" "B.Mask" "B.Paste")
			(net "LED_POSTCODE_0_R1")
		)
	)
	(footprint ""
		(layer "B.Cu")
		(at 41.966134 -47.231808)
		(property "Reference" "R818"
			(at 0 0 0)
			(layer "B.SilkS")
			(hide yes)
			(effects
				(font
					(size 1.27 1.27)
				)
				(justify mirror)
			)
		)
		(property "Value" ""
			(at 0 0 0)
			(layer "B.Fab")
			(effects
				(font
					(size 1.27 1.27)
				)
				(justify mirror)
			)
		)
		(duplicate_pad_numbers_are_jumpers no)
		(fp_line
			(start -0.7874 -0.4064)
			(end -0.7874 0.4064)
			(stroke
				(width 0.1524)
				(type default)
			)
			(layer "B.SilkS")
		)
		(fp_line
			(start -0.7874 0.4064)
			(end 0.7874 0.4064)
			(stroke
				(width 0.1524)
				(type default)
			)
			(layer "B.SilkS")
		)
		(fp_line
			(start 0.7874 -0.4064)
			(end -0.7874 -0.4064)
			(stroke
				(width 0.1524)
				(type default)
			)
			(layer "B.SilkS")
		)
		(fp_line
			(start 0.7874 0.4064)
			(end 0.7874 -0.4064)
			(stroke
				(width 0.1524)
				(type default)
			)
			(layer "B.SilkS")
		)
		(fp_line
			(start -0.67945 -0.3048)
			(end -0.67945 0.3048)
			(stroke
				(width 0.1)
				(type default)
			)
			(layer "B.Fab")
		)
		(fp_line
			(start -0.67945 0.3048)
			(end -0.120396 0.3048)
			(stroke
				(width 0.1)
				(type default)
			)
			(layer "B.Fab")
		)
		(fp_line
			(start -0.12065 -0.3048)
			(end -0.67945 -0.3048)
			(stroke
				(width 0.1)
				(type default)
			)
			(layer "B.Fab")
		)
		(fp_line
			(start -0.12065 -0.2794)
			(end -0.12065 -0.3048)
			(stroke
				(width 0.1)
				(type default)
			)
			(layer "B.Fab")
		)
		(fp_line
			(start -0.120396 0.2794)
			(end 0.12065 0.2794)
			(stroke
				(width 0.1)
				(type default)
			)
			(layer "B.Fab")
		)
		(fp_line
			(start -0.120396 0.3048)
			(end -0.120396 0.2794)
			(stroke
				(width 0.1)
				(type default)
			)
			(layer "B.Fab")
		)
		(fp_line
			(start 0.12065 -0.305054)
			(end 0.12065 -0.2794)
			(stroke
				(width 0.1)
				(type default)
			)
			(layer "B.Fab")
		)
		(fp_line
			(start 0.12065 -0.2794)
			(end -0.12065 -0.2794)
			(stroke
				(width 0.1)
				(type default)
			)
			(layer "B.Fab")
		)
		(fp_line
			(start 0.12065 0.2794)
			(end 0.12065 0.3048)
			(stroke
				(width 0.1)
				(type default)
			)
			(layer "B.Fab")
		)
		(fp_line
			(start 0.12065 0.3048)
			(end 0.67945 0.3048)
			(stroke
				(width 0.1)
				(type default)
			)
			(layer "B.Fab")
		)
		(fp_line
			(start 0.67945 -0.305054)
			(end 0.12065 -0.305054)
			(stroke
				(width 0.1)
				(type default)
			)
			(layer "B.Fab")
		)
		(fp_line
			(start 0.67945 0.3048)
			(end 0.67945 -0.305054)
			(stroke
				(width 0.1)
				(type default)
			)
			(layer "B.Fab")
		)
		(pad "1" smd circle
			(at 0.40005 0 180)
			(size 0 0)
			(layers "B.Cu" "B.Mask" "B.Paste")
			(net "SMB_BMC_MM13_R_SDA")
		)
		(pad "2" smd circle
			(at -0.40005 0 180)
			(size 0 0)
			(layers "B.Cu" "B.Mask" "B.Paste")
			(net "GND")
		)
	)
	(footprint ""
		(layer "B.Cu")
		(at 59.436 -99.06 180)
		(property "Reference" "Q8"
			(at 2.3622 1.10363 0)
			(unlocked yes)
			(layer "B.SilkS")
			(effects
				(font
					(size 0.7874 0.5842)
					(thickness 0.1524)
				)
				(justify left mirror)
			)
		)
		(property "Value" ""
			(at 0 0 0)
			(layer "B.Fab")
			(effects
				(font
					(size 1.27 1.27)
				)
				(justify mirror)
			)
		)
		(duplicate_pad_numbers_are_jumpers no)
		(fp_line
			(start 1.603248 1.500124)
			(end 1.603248 -1.500124)
			(stroke
				(width 0.1524)
				(type default)
			)
			(layer "B.SilkS")
		)
		(fp_line
			(start 1.603248 -1.500124)
			(end -1.603248 -1.500124)
			(stroke
				(width 0.1524)
				(type default)
			)
			(layer "B.SilkS")
		)
		(fp_line
			(start -1.603248 1.500124)
			(end 1.603248 1.500124)
			(stroke
				(width 0.1524)
				(type default)
			)
			(layer "B.SilkS")
		)
		(fp_line
			(start -1.603248 -1.500124)
			(end -1.603248 1.500124)
			(stroke
				(width 0.1524)
				(type default)
			)
			(layer "B.SilkS")
		)
		(fp_line
			(start 1.249934 1.169924)
			(end 0.700024 1.169924)
			(stroke
				(width 0.1)
				(type default)
			)
			(layer "B.Fab")
		)
		(fp_line
			(start 1.249934 0.729996)
			(end 1.249934 1.169924)
			(stroke
				(width 0.1)
				(type default)
			)
			(layer "B.Fab")
		)
		(fp_line
			(start 1.249934 -0.729996)
			(end 0.6985 -0.729996)
			(stroke
				(width 0.1)
				(type default)
			)
			(layer "B.Fab")
		)
		(fp_line
			(start 1.249934 -1.169924)
			(end 1.249934 -0.729996)
			(stroke
				(width 0.1)
				(type default)
			)
			(layer "B.Fab")
		)
		(fp_line
			(start 0.700024 1.500124)
			(end -0.700024 1.500124)
			(stroke
				(width 0.1)
				(type default)
			)
			(layer "B.Fab")
		)
		(fp_line
			(start 0.700024 1.169924)
			(end 0.700024 1.500124)
			(stroke
				(width 0.1)
				(type default)
			)
			(layer "B.Fab")
		)
		(fp_line
			(start 0.700024 -1.169924)
			(end 1.249934 -1.169924)
			(stroke
				(width 0.1)
				(type default)
			)
			(layer "B.Fab")
		)
		(fp_line
			(start 0.700024 -1.500124)
			(end 0.700024 -1.169924)
			(stroke
				(width 0.1)
				(type default)
			)
			(layer "B.Fab")
		)
		(fp_line
			(start 0.6985 0.729996)
			(end 1.249934 0.729996)
			(stroke
				(width 0.1)
				(type default)
			)
			(layer "B.Fab")
		)
		(fp_line
			(start 0.6985 -0.729996)
			(end 0.6985 0.729996)
			(stroke
				(width 0.1)
				(type default)
			)
			(layer "B.Fab")
		)
		(fp_line
			(start -0.700024 1.500124)
			(end -0.700024 0.219964)
			(stroke
				(width 0.1)
				(type default)
			)
			(layer "B.Fab")
		)
		(fp_line
			(start -0.700024 0.219964)
			(end -1.249934 0.219964)
			(stroke
				(width 0.1)
				(type default)
			)
			(layer "B.Fab")
		)
		(fp_line
			(start -0.700024 -0.219964)
			(end -0.700024 -1.500124)
			(stroke
				(width 0.1)
				(type default)
			)
			(layer "B.Fab")
		)
		(fp_line
			(start -0.700024 -1.500124)
			(end 0.700024 -1.500124)
			(stroke
				(width 0.1)
				(type default)
			)
			(layer "B.Fab")
		)
		(fp_line
			(start -1.249934 0.219964)
			(end -1.249934 -0.219964)
			(stroke
				(width 0.1)
				(type default)
			)
			(layer "B.Fab")
		)
		(fp_line
			(start -1.249934 -0.219964)
			(end -0.700024 -0.219964)
			(stroke
				(width 0.1)
				(type default)
			)
			(layer "B.Fab")
		)
		(fp_rect
			(start 0.700024 1.500124)
			(end -0.700024 -1.500124)
			(stroke
				(width 0)
				(type default)
			)
			(fill no)
			(layer "B.Fab")
		)
		(pad "D" smd rect
			(at -0.999998 0 90)
			(size 0.8128 0.9144)
			(layers "B.Cu" "B.Mask" "B.Paste")
			(net "FM_SOL_UART_CH_SEL_R3")
		)
		(pad "G" smd rect
			(at 0.999998 -0.94996 90)
			(size 0.8128 0.9144)
			(layers "B.Cu" "B.Mask" "B.Paste")
			(net "FM_UART_SEL_N")
		)
		(pad "S" smd rect
			(at 0.999998 0.94996 90)
			(size 0.8128 0.9144)
			(layers "B.Cu" "B.Mask" "B.Paste")
			(net "GND")
		)
	)
	(footprint ""
		(layer "B.Cu")
		(at 58.679334 -54.416198 -90)
		(property "Reference" "C69"
			(at 0 0 90)
			(layer "B.SilkS")
			(hide yes)
			(effects
				(font
					(size 1.27 1.27)
				)
				(justify mirror)
			)
		)
		(property "Value" ""
			(at 0 0 90)
			(layer "B.Fab")
			(effects
				(font
					(size 1.27 1.27)
				)
				(justify mirror)
			)
		)
		(duplicate_pad_numbers_are_jumpers no)
		(fp_line
			(start -0.7874 0.4064)
			(end 0.7874 0.4064)
			(stroke
				(width 0.1524)
				(type default)
			)
			(layer "B.SilkS")
		)
		(fp_line
			(start 0.7874 0.4064)
			(end 0.7874 -0.4064)
			(stroke
				(width 0.1524)
				(type default)
			)
			(layer "B.SilkS")
		)
		(fp_line
			(start -0.7874 -0.4064)
			(end -0.7874 0.4064)
			(stroke
				(width 0.1524)
				(type default)
			)
			(layer "B.SilkS")
		)
		(fp_line
			(start 0.7874 -0.4064)
			(end -0.7874 -0.4064)
			(stroke
				(width 0.1524)
				(type default)
			)
			(layer "B.SilkS")
		)
		(fp_line
			(start -0.67945 0.3048)
			(end -0.120396 0.3048)
			(stroke
				(width 0.1)
				(type default)
			)
			(layer "B.Fab")
		)
		(fp_line
			(start -0.120396 0.3048)
			(end -0.120396 0.2794)
			(stroke
				(width 0.1)
				(type default)
			)
			(layer "B.Fab")
		)
		(fp_line
			(start 0.12065 0.3048)
			(end 0.67945 0.3048)
			(stroke
				(width 0.1)
				(type default)
			)
			(layer "B.Fab")
		)
		(fp_line
			(start 0.67945 0.3048)
			(end 0.67945 -0.305054)
			(stroke
				(width 0.1)
				(type default)
			)
			(layer "B.Fab")
		)
		(fp_line
			(start -0.120396 0.2794)
			(end 0.12065 0.2794)
			(stroke
				(width 0.1)
				(type default)
			)
			(layer "B.Fab")
		)
		(fp_line
			(start 0.12065 0.2794)
			(end 0.12065 0.3048)
			(stroke
				(width 0.1)
				(type default)
			)
			(layer "B.Fab")
		)
		(fp_line
			(start -0.12065 -0.2794)
			(end -0.12065 -0.3048)
			(stroke
				(width 0.1)
				(type default)
			)
			(layer "B.Fab")
		)
		(fp_line
			(start 0.12065 -0.2794)
			(end -0.12065 -0.2794)
			(stroke
				(width 0.1)
				(type default)
			)
			(layer "B.Fab")
		)
		(fp_line
			(start -0.67945 -0.3048)
			(end -0.67945 0.3048)
			(stroke
				(width 0.1)
				(type default)
			)
			(layer "B.Fab")
		)
		(fp_line
			(start -0.12065 -0.3048)
			(end -0.67945 -0.3048)
			(stroke
				(width 0.1)
				(type default)
			)
			(layer "B.Fab")
		)
		(fp_line
			(start 0.12065 -0.305054)
			(end 0.12065 -0.2794)
			(stroke
				(width 0.1)
				(type default)
			)
			(layer "B.Fab")
		)
		(fp_line
			(start 0.67945 -0.305054)
			(end 0.12065 -0.305054)
			(stroke
				(width 0.1)
				(type default)
			)
			(layer "B.Fab")
		)
		(pad "1" smd circle
			(at 0.40005 0 90)
			(size 0 0)
			(layers "B.Cu" "B.Mask" "B.Paste")
			(net "P1V8_STBY_PE_VCC18A")
		)
		(pad "2" smd circle
			(at -0.40005 0 90)
			(size 0 0)
			(layers "B.Cu" "B.Mask" "B.Paste")
			(net "GND")
		)
	)
	(footprint ""
		(layer "B.Cu")
		(at 20.066 -24.003 -90)
		(property "Reference" "PC269"
			(at 0 0 90)
			(layer "B.SilkS")
			(hide yes)
			(effects
				(font
					(size 1.27 1.27)
				)
				(justify mirror)
			)
		)
		(property "Value" ""
			(at 0 0 90)
			(layer "B.Fab")
			(effects
				(font
					(size 1.27 1.27)
				)
				(justify mirror)
			)
		)
		(duplicate_pad_numbers_are_jumpers no)
		(fp_line
			(start -1.651 0.8382)
			(end 1.651 0.8382)
			(stroke
				(width 0.1524)
				(type default)
			)
			(layer "B.SilkS")
		)
		(fp_line
			(start 0 0.8382)
			(end 0 -0.8382)
			(stroke
				(width 0.1524)
				(type default)
			)
			(layer "B.SilkS")
		)
		(fp_line
			(start 1.651 0.8382)
			(end 1.651 -0.8382)
			(stroke
				(width 0.1524)
				(type default)
			)
			(layer "B.SilkS")
		)
		(fp_line
			(start -1.651 -0.8382)
			(end -1.651 0.8382)
			(stroke
				(width 0.1524)
				(type default)
			)
			(layer "B.SilkS")
		)
		(fp_line
			(start 1.651 -0.8382)
			(end -1.651 -0.8382)
			(stroke
				(width 0.1524)
				(type default)
			)
			(layer "B.SilkS")
		)
		(fp_line
			(start -1.55956 0.7366)
			(end -1.55956 -0.7366)
			(stroke
				(width 0.1)
				(type default)
			)
			(layer "B.Fab")
		)
		(fp_line
			(start -1.524 0.7366)
			(end -1.55956 0.7366)
			(stroke
				(width 0.1)
				(type default)
			)
			(layer "B.Fab")
		)
		(fp_line
			(start 1.524 0.7366)
			(end -1.524 0.7366)
			(stroke
				(width 0.1)
				(type default)
			)
			(layer "B.Fab")
		)
		(fp_line
			(start 1.55956 0.7366)
			(end 1.524 0.7366)
			(stroke
				(width 0.1)
				(type default)
			)
			(layer "B.Fab")
		)
		(fp_line
			(start -1.55956 -0.7366)
			(end -1.524 -0.7366)
			(stroke
				(width 0.1)
				(type default)
			)
			(layer "B.Fab")
		)
		(fp_line
			(start -1.524 -0.7366)
			(end 1.524 -0.7366)
			(stroke
				(width 0.1)
				(type default)
			)
			(layer "B.Fab")
		)
		(fp_line
			(start 1.524 -0.7366)
			(end 1.55956 -0.7366)
			(stroke
				(width 0.1)
				(type default)
			)
			(layer "B.Fab")
		)
		(fp_line
			(start 1.55956 -0.7366)
			(end 1.55956 0.7366)
			(stroke
				(width 0.1)
				(type default)
			)
			(layer "B.Fab")
		)
		(pad "1" smd rect
			(at 0.94996 0 270)
			(size 1.1176 1.3716)
			(layers "B.Cu" "B.Mask" "B.Paste")
			(net "P1V0_AUX")
		)
		(pad "2" smd rect
			(at -0.94996 0 270)
			(size 1.1176 1.3716)
			(layers "B.Cu" "B.Mask" "B.Paste")
			(net "GND")
		)
	)
)
